# S9S_MB_2U (Grand Teton) — schematic netlist excerpt (pin names and nets, part order shuffled) for the footprints in the layout excerpt that follows; sources: Cadence DE-HDL packaged netlist, KiCad conversion of 03242023_DA0F0TMBIJ0_F0T_Motherboard_J_brd_V01_OCP.brd

R424  Q_RES  33.2 1% CHIP  pkg 0402LF  page 153 : A = SMB_OCP_SFF_3V3AUX_BUF_R_SCL ; B = SMB_OCP_SFF_3V3AUX_BUF_SCL
R745  Q_RES  33.2 1% CHIP  pkg 0402LF  page 133 : A = FM_CPU_EN ; B = FM_CPU_EN_R

(kicad_pcb
	(version 20260206)
	(generator "pcbnew")
	(generator_version "10.0")
	(general
		(thickness 1.6)
		(legacy_teardrops no)
	)
	(paper "A4")
	(title_block
		(title "03242023_DA0F0TMBIJ0_F0T_Motherboard_J_brd_V01_OCP.brd")
		(comment 1 "Grand Teton / footprints 4425-4426 of 6105")
	)
	(layers
		(0 "F.Cu" signal "TOP")
		(4 "In1.Cu" signal "GND")
		(6 "In2.Cu" signal "IN1")
		(8 "In3.Cu" signal "GND1")
		(10 "In4.Cu" signal "IN2")
		(12 "In5.Cu" signal "GND2")
		(14 "In6.Cu" signal "IN3")
		(16 "In7.Cu" signal "GND3")
		(18 "In8.Cu" signal "VCC")
		(20 "In9.Cu" signal "VCC1")
		(22 "In10.Cu" signal "GND4")
		(24 "In11.Cu" signal "IN4")
		(26 "In12.Cu" signal "GND5")
		(28 "In13.Cu" signal "IN5")
		(30 "In14.Cu" signal "GND6")
		(32 "In15.Cu" signal "IN6")
		(34 "In16.Cu" signal "GND7")
		(2 "B.Cu" signal "BOTTOM")
		(9 "F.Adhes" user "F.Adhesive")
		(11 "B.Adhes" user "B.Adhesive")
		(13 "F.Paste" user "Package Geometry/Pastemask Top")
		(15 "B.Paste" user "Package Geometry/Pastemask Bottom")
		(5 "F.SilkS" user "Ref Des/Silkscreen Top")
		(7 "B.SilkS" user "Ref Des/Silkscreen Bottom")
		(1 "F.Mask" user "Board Geometry/Soldermask Top")
		(3 "B.Mask" user "Board Geometry/Soldermask Bottom")
		(17 "Dwgs.User" user "User.Drawings")
		(19 "Cmts.User" user "User.Comments")
		(21 "Eco1.User" user "User.Eco1")
		(23 "Eco2.User" user "User.Eco2")
		(25 "Edge.Cuts" user "Board Geometry/Outline")
		(27 "Margin" user)
		(31 "F.CrtYd" user "Package Geometry/Place Bound Top")
		(29 "B.CrtYd" user "Package Geometry/Place Bound Bottom")
		(35 "F.Fab" user "Ref Des/Assembly Top")
		(33 "B.Fab" user "Ref Des/Assembly Bottom")
	)
	(footprint ""
		(layer "B.Cu")
		(at 450.43725 -45.288962)
		(property "Reference" "R424"
			(at 0 0 0)
			(layer "B.SilkS")
			(hide yes)
			(effects
				(font
					(size 1.27 1.27)
				)
				(justify mirror)
			)
		)
		(property "Value" ""
			(at 0 0 0)
			(layer "B.Fab")
			(effects
				(font
					(size 1.27 1.27)
				)
				(justify mirror)
			)
		)
		(duplicate_pad_numbers_are_jumpers no)
		(fp_line
			(start -0.7874 -0.4064)
			(end -0.7874 0.4064)
			(stroke
				(width 0.1524)
				(type default)
			)
			(layer "B.SilkS")
		)
		(fp_line
			(start -0.7874 0.4064)
			(end 0.7874 0.4064)
			(stroke
				(width 0.1524)
				(type default)
			)
			(layer "B.SilkS")
		)
		(fp_line
			(start 0.7874 -0.4064)
			(end -0.7874 -0.4064)
			(stroke
				(width 0.1524)
				(type default)
			)
			(layer "B.SilkS")
		)
		(fp_line
			(start 0.7874 0.4064)
			(end 0.7874 -0.4064)
			(stroke
				(width 0.1524)
				(type default)
			)
			(layer "B.SilkS")
		)
		(fp_line
			(start -0.67945 -0.3048)
			(end -0.67945 0.3048)
			(stroke
				(width 0.1)
				(type default)
			)
			(layer "B.Fab")
		)
		(fp_line
			(start -0.67945 0.3048)
			(end -0.120396 0.3048)
			(stroke
				(width 0.1)
				(type default)
			)
			(layer "B.Fab")
		)
		(fp_line
			(start -0.12065 -0.3048)
			(end -0.67945 -0.3048)
			(stroke
				(width 0.1)
				(type default)
			)
			(layer "B.Fab")
		)
		(fp_line
			(start -0.12065 -0.2794)
			(end -0.12065 -0.3048)
			(stroke
				(width 0.1)
				(type default)
			)
			(layer "B.Fab")
		)
		(fp_line
			(start -0.120396 0.2794)
			(end 0.12065 0.2794)
			(stroke
				(width 0.1)
				(type default)
			)
			(layer "B.Fab")
		)
		(fp_line
			(start -0.120396 0.3048)
			(end -0.120396 0.2794)
			(stroke
				(width 0.1)
				(type default)
			)
			(layer "B.Fab")
		)
		(fp_line
			(start 0.12065 -0.305054)
			(end 0.12065 -0.2794)
			(stroke
				(width 0.1)
				(type default)
			)
			(layer "B.Fab")
		)
		(fp_line
			(start 0.12065 -0.2794)
			(end -0.12065 -0.2794)
			(stroke
				(width 0.1)
				(type default)
			)
			(layer "B.Fab")
		)
		(fp_line
			(start 0.12065 0.2794)
			(end 0.12065 0.3048)
			(stroke
				(width 0.1)
				(type default)
			)
			(layer "B.Fab")
		)
		(fp_line
			(start 0.12065 0.3048)
			(end 0.67945 0.3048)
			(stroke
				(width 0.1)
				(type default)
			)
			(layer "B.Fab")
		)
		(fp_line
			(start 0.67945 -0.305054)
			(end 0.12065 -0.305054)
			(stroke
				(width 0.1)
				(type default)
			)
			(layer "B.Fab")
		)
		(fp_line
			(start 0.67945 0.3048)
			(end 0.67945 -0.305054)
			(stroke
				(width 0.1)
				(type default)
			)
			(layer "B.Fab")
		)
		(pad "1" smd circle
			(at 0.40005 0 180)
			(size 0 0)
			(layers "B.Cu" "B.Mask" "B.Paste")
			(net "SMB_OCP_SFF_3V3AUX_BUF_R_SCL")
		)
		(pad "2" smd circle
			(at -0.40005 0 180)
			(size 0 0)
			(layers "B.Cu" "B.Mask" "B.Paste")
			(net "SMB_OCP_SFF_3V3AUX_BUF_SCL")
		)
	)
	(footprint ""
		(layer "B.Cu")
		(at 195.246498 -191.307466 180)
		(property "Reference" "R745"
			(at 0 0 0)
			(layer "B.SilkS")
			(hide yes)
			(effects
				(font
					(size 1.27 1.27)
				)
				(justify mirror)
			)
		)
		(property "Value" ""
			(at 0 0 0)
			(layer "B.Fab")
			(effects
				(font
					(size 1.27 1.27)
				)
				(justify mirror)
			)
		)
		(duplicate_pad_numbers_are_jumpers no)
		(fp_line
			(start 0.7874 0.4064)
			(end 0.7874 -0.4064)
			(stroke
				(width 0.1524)
				(type default)
			)
			(layer "B.SilkS")
		)
		(fp_line
			(start 0.7874 -0.4064)
			(end -0.7874 -0.4064)
			(stroke
				(width 0.1524)
				(type default)
			)
			(layer "B.SilkS")
		)
		(fp_line
			(start -0.7874 0.4064)
			(end 0.7874 0.4064)
			(stroke
				(width 0.1524)
				(type default)
			)
			(layer "B.SilkS")
		)
		(fp_line
			(start -0.7874 -0.4064)
			(end -0.7874 0.4064)
			(stroke
				(width 0.1524)
				(type default)
			)
			(layer "B.SilkS")
		)
		(fp_line
			(start 0.67945 0.3048)
			(end 0.67945 -0.305054)
			(stroke
				(width 0.1)
				(type default)
			)
			(layer "B.Fab")
		)
		(fp_line
			(start 0.67945 -0.305054)
			(end 0.12065 -0.305054)
			(stroke
				(width 0.1)
				(type default)
			)
			(layer "B.Fab")
		)
		(fp_line
			(start 0.12065 0.3048)
			(end 0.67945 0.3048)
			(stroke
				(width 0.1)
				(type default)
			)
			(layer "B.Fab")
		)
		(fp_line
			(start 0.12065 0.2794)
			(end 0.12065 0.3048)
			(stroke
				(width 0.1)
				(type default)
			)
			(layer "B.Fab")
		)
		(fp_line
			(start 0.12065 -0.2794)
			(end -0.12065 -0.2794)
			(stroke
				(width 0.1)
				(type default)
			)
			(layer "B.Fab")
		)
		(fp_line
			(start 0.12065 -0.305054)
			(end 0.12065 -0.2794)
			(stroke
				(width 0.1)
				(type default)
			)
			(layer "B.Fab")
		)
		(fp_line
			(start -0.120396 0.3048)
			(end -0.120396 0.2794)
			(stroke
				(width 0.1)
				(type default)
			)
			(layer "B.Fab")
		)
		(fp_line
			(start -0.120396 0.2794)
			(end 0.12065 0.2794)
			(stroke
				(width 0.1)
				(type default)
			)
			(layer "B.Fab")
		)
		(fp_line
			(start -0.12065 -0.2794)
			(end -0.12065 -0.3048)
			(stroke
				(width 0.1)
				(type default)
			)
			(layer "B.Fab")
		)
		(fp_line
			(start -0.12065 -0.3048)
			(end -0.67945 -0.3048)
			(stroke
				(width 0.1)
				(type default)
			)
			(layer "B.Fab")
		)
		(fp_line
			(start -0.67945 0.3048)
			(end -0.120396 0.3048)
			(stroke
				(width 0.1)
				(type default)
			)
			(layer "B.Fab")
		)
		(fp_line
			(start -0.67945 -0.3048)
			(end -0.67945 0.3048)
			(stroke
				(width 0.1)
				(type default)
			)
			(layer "B.Fab")
		)
		(pad "1" smd circle
			(at 0.40005 0)
			(size 0 0)
			(layers "B.Cu" "B.Mask" "B.Paste")
			(net "FM_CPU_EN")
		)
		(pad "2" smd circle
			(at -0.40005 0)
			(size 0 0)
			(layers "B.Cu" "B.Mask" "B.Paste")
			(net "FM_CPU_EN_R")
		)
	)
)
